# T6G (Grand Teton) — schematic netlist excerpt (pin names and nets, part order shuffled) for the footprints in the layout excerpt that follows; sources: Cadence DE-HDL packaged netlist, KiCad conversion of 04192023_DAF0TMB3IC0_F0TG_MB_C_brd_V02_OCP.brd

PD107  DIODE_TVS  SMF14A IC  pkg SOD123F  page 140 : A = GND ; C = P12V_AUX
R177  Q_RES  33 5% CHIP  pkg 0402LF  page 209 : A = PWRGD_PVDD18_S5_P0 ; B = FM_PWRGD_PVDD18_S5_P0

(kicad_pcb
	(version 20260206)
	(generator "pcbnew")
	(generator_version "10.0")
	(general
		(thickness 1.6)
		(legacy_teardrops no)
	)
	(paper "A4")
	(title_block
		(title "04192023_DAF0TMB3IC0_F0TG_MB_C_brd_V02_OCP.brd")
		(comment 1 "Grand Teton / footprints 961-963 of 8354")
	)
	(layers
		(0 "F.Cu" signal "TOP")
		(4 "In1.Cu" signal "GND")
		(6 "In2.Cu" signal "IN1")
		(8 "In3.Cu" signal "GND1")
		(10 "In4.Cu" signal "IN2")
		(12 "In5.Cu" signal "GND2")
		(14 "In6.Cu" signal "IN3")
		(16 "In7.Cu" signal "GND3")
		(18 "In8.Cu" signal "VCC")
		(20 "In9.Cu" signal "VCC1")
		(22 "In10.Cu" signal "GND4")
		(24 "In11.Cu" signal "IN4")
		(26 "In12.Cu" signal "GND5")
		(28 "In13.Cu" signal "IN5")
		(30 "In14.Cu" signal "GND6")
		(32 "In15.Cu" signal "IN6")
		(34 "In16.Cu" signal "GND7")
		(2 "B.Cu" signal "BOTTOM")
		(9 "F.Adhes" user "F.Adhesive")
		(11 "B.Adhes" user "B.Adhesive")
		(13 "F.Paste" user "Package Geometry/Pastemask Top")
		(15 "B.Paste" user "Package Geometry/Pastemask Bottom")
		(5 "F.SilkS" user "Ref Des/Silkscreen Top")
		(7 "B.SilkS" user "Ref Des/Silkscreen Bottom")
		(1 "F.Mask" user "Board Geometry/Soldermask Top")
		(3 "B.Mask" user "Board Geometry/Soldermask Bottom")
		(17 "Dwgs.User" user "User.Drawings")
		(19 "Cmts.User" user "User.Comments")
		(21 "Eco1.User" user "User.Eco1")
		(23 "Eco2.User" user "User.Eco2")
		(25 "Edge.Cuts" user "Board Geometry/Outline")
		(27 "Margin" user)
		(31 "F.CrtYd" user "Package Geometry/Place Bound Top")
		(29 "B.CrtYd" user "Package Geometry/Place Bound Bottom")
		(35 "F.Fab" user "Ref Des/Assembly Top")
		(33 "B.Fab" user "Ref Des/Assembly Bottom")
	)
	(footprint ""
		(layer "F.Cu")
		(at 197.269608 -111.593376 180)
		(property "Reference" "R177"
			(at 0 0 180)
			(layer "F.SilkS")
			(hide yes)
			(effects
				(font
					(size 1.27 1.27)
				)
			)
		)
		(property "Value" ""
			(at 0 0 180)
			(layer "F.Fab")
			(effects
				(font
					(size 1.27 1.27)
				)
			)
		)
		(duplicate_pad_numbers_are_jumpers no)
		(fp_line
			(start 0.7874 0.4064)
			(end -0.7874 0.4064)
			(stroke
				(width 0.1524)
				(type default)
			)
			(layer "F.SilkS")
		)
		(fp_line
			(start 0.7874 -0.4064)
			(end 0.7874 0.4064)
			(stroke
				(width 0.1524)
				(type default)
			)
			(layer "F.SilkS")
		)
		(fp_line
			(start -0.7874 0.4064)
			(end -0.7874 -0.4064)
			(stroke
				(width 0.1524)
				(type default)
			)
			(layer "F.SilkS")
		)
		(fp_line
			(start -0.7874 -0.4064)
			(end 0.7874 -0.4064)
			(stroke
				(width 0.1524)
				(type default)
			)
			(layer "F.SilkS")
		)
		(fp_line
			(start 0.67945 0.3048)
			(end 0.120396 0.3048)
			(stroke
				(width 0.1)
				(type default)
			)
			(layer "F.Fab")
		)
		(fp_line
			(start 0.67945 -0.3048)
			(end 0.67945 0.3048)
			(stroke
				(width 0.1)
				(type default)
			)
			(layer "F.Fab")
		)
		(fp_line
			(start 0.12065 -0.2794)
			(end 0.12065 -0.3048)
			(stroke
				(width 0.1)
				(type default)
			)
			(layer "F.Fab")
		)
		(fp_line
			(start 0.12065 -0.3048)
			(end 0.67945 -0.3048)
			(stroke
				(width 0.1)
				(type default)
			)
			(layer "F.Fab")
		)
		(fp_line
			(start 0.120396 0.3048)
			(end 0.120396 0.2794)
			(stroke
				(width 0.1)
				(type default)
			)
			(layer "F.Fab")
		)
		(fp_line
			(start 0.120396 0.2794)
			(end -0.12065 0.2794)
			(stroke
				(width 0.1)
				(type default)
			)
			(layer "F.Fab")
		)
		(fp_line
			(start -0.12065 0.3048)
			(end -0.67945 0.3048)
			(stroke
				(width 0.1)
				(type default)
			)
			(layer "F.Fab")
		)
		(fp_line
			(start -0.12065 0.2794)
			(end -0.12065 0.3048)
			(stroke
				(width 0.1)
				(type default)
			)
			(layer "F.Fab")
		)
		(fp_line
			(start -0.12065 -0.2794)
			(end 0.12065 -0.2794)
			(stroke
				(width 0.1)
				(type default)
			)
			(layer "F.Fab")
		)
		(fp_line
			(start -0.12065 -0.305054)
			(end -0.12065 -0.2794)
			(stroke
				(width 0.1)
				(type default)
			)
			(layer "F.Fab")
		)
		(fp_line
			(start -0.67945 0.3048)
			(end -0.67945 -0.305054)
			(stroke
				(width 0.1)
				(type default)
			)
			(layer "F.Fab")
		)
		(fp_line
			(start -0.67945 -0.305054)
			(end -0.12065 -0.305054)
			(stroke
				(width 0.1)
				(type default)
			)
			(layer "F.Fab")
		)
		(pad "1" smd circle
			(at -0.40005 0 180)
			(size 0 0)
			(layers "F.Cu" "F.Mask" "F.Paste")
			(net "PWRGD_PVDD18_S5_P0")
		)
		(pad "2" smd circle
			(at 0.40005 0 180)
			(size 0 0)
			(layers "F.Cu" "F.Mask" "F.Paste")
			(net "FM_PWRGD_PVDD18_S5_P0")
		)
	)
	(footprint ""
		(layer "F.Cu")
		(at 77.915262 -30.112462 -90)
		(property "Reference" "PD107"
			(at 2.145792 -2.517648 90)
			(unlocked yes)
			(layer "F.SilkS")
			(effects
				(font
					(size 0.7874 0.5842)
					(thickness 0.1524)
				)
				(justify left)
			)
		)
		(property "Value" ""
			(at 0 0 270)
			(layer "F.Fab")
			(effects
				(font
					(size 1.27 1.27)
				)
			)
		)
		(duplicate_pad_numbers_are_jumpers no)
		(fp_line
			(start -2.250186 0.999998)
			(end 2.631186 0.999998)
			(stroke
				(width 0.1524)
				(type default)
			)
			(layer "F.SilkS")
		)
		(fp_line
			(start 2.631186 0.999998)
			(end 2.631186 -0.999998)
			(stroke
				(width 0.1524)
				(type default)
			)
			(layer "F.SilkS")
		)
		(fp_line
			(start -0.381 0.3302)
			(end -0.381 -0.4318)
			(stroke
				(width 0.1524)
				(type default)
			)
			(layer "F.SilkS")
		)
		(fp_line
			(start -0.381 -0.0508)
			(end -0.6604 -0.0508)
			(stroke
				(width 0.1524)
				(type default)
			)
			(layer "F.SilkS")
		)
		(fp_line
			(start 0.381 -0.0508)
			(end -0.381 0.3302)
			(stroke
				(width 0.1524)
				(type default)
			)
			(layer "F.SilkS")
		)
		(fp_line
			(start 0.381 -0.0508)
			(end 0.635 -0.0508)
			(stroke
				(width 0.1524)
				(type default)
			)
			(layer "F.SilkS")
		)
		(fp_line
			(start -0.381 -0.4318)
			(end 0.381 -0.0508)
			(stroke
				(width 0.1524)
				(type default)
			)
			(layer "F.SilkS")
		)
		(fp_line
			(start 0.381 -0.4318)
			(end 0.381 0.3302)
			(stroke
				(width 0.1524)
				(type default)
			)
			(layer "F.SilkS")
		)
		(fp_line
			(start -2.250186 -0.999998)
			(end -2.250186 0.999998)
			(stroke
				(width 0.1524)
				(type default)
			)
			(layer "F.SilkS")
		)
		(fp_line
			(start 2.631186 -0.999998)
			(end -2.250186 -0.999998)
			(stroke
				(width 0.1524)
				(type default)
			)
			(layer "F.SilkS")
		)
		(fp_rect
			(start 2.6162 1.016)
			(end 2.1844 -0.9652)
			(stroke
				(width 0)
				(type default)
			)
			(fill yes)
			(layer "F.SilkS")
		)
		(fp_line
			(start -1.450086 0.999998)
			(end 1.450086 0.999998)
			(stroke
				(width 0.1)
				(type default)
			)
			(layer "F.Fab")
		)
		(fp_line
			(start 1.450086 0.999998)
			(end 1.450086 -0.999998)
			(stroke
				(width 0.1)
				(type default)
			)
			(layer "F.Fab")
		)
		(fp_line
			(start -1.450086 -0.999998)
			(end -1.450086 0.999998)
			(stroke
				(width 0.1)
				(type default)
			)
			(layer "F.Fab")
		)
		(fp_line
			(start 1.450086 -0.999998)
			(end -1.450086 -0.999998)
			(stroke
				(width 0.1)
				(type default)
			)
			(layer "F.Fab")
		)
		(fp_text user "+"
			(at -3.849878 -0.100584 270)
			(unlocked yes)
			(layer "F.SilkS")
			(effects
				(font
					(size 1.905 1.4224)
					(thickness 0.1524)
				)
				(justify left)
			)
		)
		(fp_text user "-"
			(at 2.4384 -0.22225 270)
			(unlocked yes)
			(layer "F.SilkS")
			(effects
				(font
					(size 1.905 1.4224)
					(thickness 0.1524)
				)
				(justify left)
			)
		)
		(fp_text user "+"
			(at -3.4798 -0.22225 270)
			(unlocked yes)
			(layer "F.Fab")
			(effects
				(font
					(size 1.905 1.4224)
					(thickness 0.1524)
				)
				(justify left)
			)
		)
		(fp_text user "-"
			(at 2.4384 -0.22225 270)
			(unlocked yes)
			(layer "F.Fab")
			(effects
				(font
					(size 1.905 1.4224)
					(thickness 0.1524)
				)
				(justify left)
			)
		)
		(pad "A" smd rect
			(at -1.450086 0 270)
			(size 1.3208 1.4224)
			(layers "F.Cu" "F.Mask" "F.Paste")
			(net "GND")
		)
		(pad "C" smd rect
			(at 1.450086 0 270)
			(size 1.3208 1.4224)
			(layers "F.Cu" "F.Mask" "F.Paste")
			(net "P12V_AUX")
		)
	)
	(footprint ""
		(layer "F.Cu")
		(at 381.762 -103.378)
		(property "Reference" "ME15"
			(at 0 0 0)
			(layer "F.SilkS")
			(hide yes)
			(effects
				(font
					(size 1.27 1.27)
				)
			)
		)
		(property "Value" ""
			(at 0 0 0)
			(layer "F.Fab")
			(effects
				(font
					(size 1.27 1.27)
				)
			)
		)
		(duplicate_pad_numbers_are_jumpers no)
		(zone
			(layer "F.Cu")
			(hatch none 0.5)
			(connect_pads
				(clearance 0)
			)
			(min_thickness 0.25)
			(keepout
				(tracks allowed)
				(vias allowed)
				(pads allowed)
				(copperpour allowed)
				(footprints not_allowed)
			)
			(placement
				(enabled no)
				(sheetname "")
			)
			(fill
				(thermal_gap 0.5)
				(thermal_bridge_width 0.5)
				(island_removal_mode 0)
			)
			(polygon
				(pts
					(arc
						(start 391.76198 -103.378)
						(mid 371.76202 -103.378)
						(end 391.76198 -103.378)
					)
				)
			)
		)
	)
)
